(kicad_pcb
	(version 20260206)
	(generator "pcbnew")
	(generator_version "10.0")
	(general
		(thickness 1.6)
		(legacy_teardrops no)
	)
	(paper "A4")
	(title_block
		(title "01162023_DA0F0TEBIF0_F0T_Expander_BD_F_brd_V02_OCP.brd")
		(comment 1 "Grand Teton / footprints 6813-6818 of 9728")
	)
	(layers
		(0 "F.Cu" signal "TOP")
		(4 "In1.Cu" signal "GND")
		(6 "In2.Cu" signal "VCC")
		(8 "In3.Cu" signal "VCC1")
		(10 "In4.Cu" signal "GND1")
		(12 "In5.Cu" signal "IN1")
		(14 "In6.Cu" signal "GND2")
		(16 "In7.Cu" signal "IN2")
		(18 "In8.Cu" signal "GND3")
		(20 "In9.Cu" signal "IN3")
		(22 "In10.Cu" signal "GND4")
		(24 "In11.Cu" signal "IN4")
		(26 "In12.Cu" signal "GND5")
		(28 "In13.Cu" signal "IN5")
		(30 "In14.Cu" signal "GND6")
		(32 "In15.Cu" signal "IN6")
		(34 "In16.Cu" signal "GND7")
		(2 "B.Cu" signal "BOTTOM")
		(9 "F.Adhes" user "F.Adhesive")
		(11 "B.Adhes" user "B.Adhesive")
		(13 "F.Paste" user "Package Geometry/Pastemask Top")
		(15 "B.Paste" user "Package Geometry/Pastemask Bottom")
		(5 "F.SilkS" user "Ref Des/Silkscreen Top")
		(7 "B.SilkS" user "Ref Des/Silkscreen Bottom")
		(1 "F.Mask" user "Board Geometry/Soldermask Top")
		(3 "B.Mask" user "Board Geometry/Soldermask Bottom")
		(17 "Dwgs.User" user "User.Drawings")
		(19 "Cmts.User" user "User.Comments")
		(21 "Eco1.User" user "User.Eco1")
		(23 "Eco2.User" user "User.Eco2")
		(25 "Edge.Cuts" user "Board Geometry/Outline")
		(27 "Margin" user)
		(31 "F.CrtYd" user "Package Geometry/Place Bound Top")
		(29 "B.CrtYd" user "Package Geometry/Place Bound Bottom")
		(35 "F.Fab" user "Ref Des/Assembly Top")
		(33 "B.Fab" user "Ref Des/Assembly Bottom")
	)
	(footprint ""
		(layer "F.Cu")
		(at 308.473856 -26.31186 -90)
		(property "Reference" "U410"
			(at -0.15494 -2.321814 90)
			(unlocked yes)
			(layer "F.SilkS")
			(effects
				(font
					(size 0.7874 0.5842)
					(thickness 0.1524)
				)
			)
		)
		(property "Value" ""
			(at 0 0 270)
			(layer "F.Fab")
			(effects
				(font
					(size 1.27 1.27)
				)
			)
		)
		(duplicate_pad_numbers_are_jumpers no)
		(fp_line
			(start -1.949958 1.610106)
			(end -1.949958 -1.610106)
			(stroke
				(width 0.1524)
				(type default)
			)
			(layer "F.SilkS")
		)
		(fp_line
			(start 1.949958 1.610106)
			(end -1.949958 1.610106)
			(stroke
				(width 0.1524)
				(type default)
			)
			(layer "F.SilkS")
		)
		(fp_line
			(start 1.949958 -1.560068)
			(end 1.949958 1.610106)
			(stroke
				(width 0.1524)
				(type default)
			)
			(layer "F.SilkS")
		)
		(fp_line
			(start -1.949958 -1.610106)
			(end 1.949958 -1.610106)
			(stroke
				(width 0.1524)
				(type default)
			)
			(layer "F.SilkS")
		)
		(fp_line
			(start -0.750062 1.560068)
			(end -0.750062 -1.560068)
			(stroke
				(width 0.1)
				(type default)
			)
			(layer "F.Fab")
		)
		(fp_line
			(start 0.750062 1.560068)
			(end -0.750062 1.560068)
			(stroke
				(width 0.1)
				(type default)
			)
			(layer "F.Fab")
		)
		(fp_line
			(start -0.750062 -1.560068)
			(end 0.750062 -1.560068)
			(stroke
				(width 0.1)
				(type default)
			)
			(layer "F.Fab")
		)
		(fp_line
			(start 0.750062 -1.560068)
			(end 0.750062 1.560068)
			(stroke
				(width 0.1)
				(type default)
			)
			(layer "F.Fab")
		)
		(pad "D" smd rect
			(at 1.100074 0 180)
			(size 1.016 1.4224)
			(layers "F.Cu" "F.Mask" "F.Paste")
			(net "SSD10_LED_ISO_N")
		)
		(pad "G" smd rect
			(at -1.100074 -0.94996 180)
			(size 1.016 1.4224)
			(layers "F.Cu" "F.Mask" "F.Paste")
			(net "SSD10_LED_R")
		)
		(pad "S" smd rect
			(at -1.100074 0.94996 180)
			(size 1.016 1.4224)
			(layers "F.Cu" "F.Mask" "F.Paste")
			(net "GND")
		)
	)
	(footprint ""
		(layer "F.Cu")
		(at 112.475772 -279.101804)
		(property "Reference" "PC75"
			(at 0 0 0)
			(layer "F.SilkS")
			(hide yes)
			(effects
				(font
					(size 1.27 1.27)
				)
			)
		)
		(property "Value" ""
			(at 0 0 0)
			(layer "F.Fab")
			(effects
				(font
					(size 1.27 1.27)
				)
			)
		)
		(duplicate_pad_numbers_are_jumpers no)
		(fp_line
			(start -0.7874 -0.4064)
			(end 0.7874 -0.4064)
			(stroke
				(width 0.1524)
				(type default)
			)
			(layer "F.SilkS")
		)
		(fp_line
			(start -0.7874 0.4064)
			(end -0.7874 -0.4064)
			(stroke
				(width 0.1524)
				(type default)
			)
			(layer "F.SilkS")
		)
		(fp_line
			(start 0.7874 -0.4064)
			(end 0.7874 0.4064)
			(stroke
				(width 0.1524)
				(type default)
			)
			(layer "F.SilkS")
		)
		(fp_line
			(start 0.7874 0.4064)
			(end -0.7874 0.4064)
			(stroke
				(width 0.1524)
				(type default)
			)
			(layer "F.SilkS")
		)
		(fp_line
			(start -0.67945 -0.305054)
			(end -0.12065 -0.305054)
			(stroke
				(width 0.1)
				(type default)
			)
			(layer "F.Fab")
		)
		(fp_line
			(start -0.67945 0.3048)
			(end -0.67945 -0.305054)
			(stroke
				(width 0.1)
				(type default)
			)
			(layer "F.Fab")
		)
		(fp_line
			(start -0.12065 -0.305054)
			(end -0.12065 -0.2794)
			(stroke
				(width 0.1)
				(type default)
			)
			(layer "F.Fab")
		)
		(fp_line
			(start -0.12065 -0.2794)
			(end 0.12065 -0.2794)
			(stroke
				(width 0.1)
				(type default)
			)
			(layer "F.Fab")
		)
		(fp_line
			(start -0.12065 0.2794)
			(end -0.12065 0.3048)
			(stroke
				(width 0.1)
				(type default)
			)
			(layer "F.Fab")
		)
		(fp_line
			(start -0.12065 0.3048)
			(end -0.67945 0.3048)
			(stroke
				(width 0.1)
				(type default)
			)
			(layer "F.Fab")
		)
		(fp_line
			(start 0.120396 0.2794)
			(end -0.12065 0.2794)
			(stroke
				(width 0.1)
				(type default)
			)
			(layer "F.Fab")
		)
		(fp_line
			(start 0.120396 0.3048)
			(end 0.120396 0.2794)
			(stroke
				(width 0.1)
				(type default)
			)
			(layer "F.Fab")
		)
		(fp_line
			(start 0.12065 -0.3048)
			(end 0.67945 -0.3048)
			(stroke
				(width 0.1)
				(type default)
			)
			(layer "F.Fab")
		)
		(fp_line
			(start 0.12065 -0.2794)
			(end 0.12065 -0.3048)
			(stroke
				(width 0.1)
				(type default)
			)
			(layer "F.Fab")
		)
		(fp_line
			(start 0.67945 -0.3048)
			(end 0.67945 0.3048)
			(stroke
				(width 0.1)
				(type default)
			)
			(layer "F.Fab")
		)
		(fp_line
			(start 0.67945 0.3048)
			(end 0.120396 0.3048)
			(stroke
				(width 0.1)
				(type default)
			)
			(layer "F.Fab")
		)
		(pad "1" smd circle
			(at -0.40005 0)
			(size 0 0)
			(layers "F.Cu" "F.Mask" "F.Paste")
			(net "SW_P12V_P0V8_PEX0_FLT")
		)
		(pad "2" smd circle
			(at 0.40005 0)
			(size 0 0)
			(layers "F.Cu" "F.Mask" "F.Paste")
			(net "GND")
		)
	)
	(footprint ""
		(layer "F.Cu")
		(at 399.364454 -29.079952 180)
		(property "Reference" "R6211"
			(at 0 0 180)
			(layer "F.SilkS")
			(hide yes)
			(effects
				(font
					(size 1.27 1.27)
				)
			)
		)
		(property "Value" ""
			(at 0 0 180)
			(layer "F.Fab")
			(effects
				(font
					(size 1.27 1.27)
				)
			)
		)
		(duplicate_pad_numbers_are_jumpers no)
		(fp_line
			(start 0.7874 0.4064)
			(end -0.7874 0.4064)
			(stroke
				(width 0.1524)
				(type default)
			)
			(layer "F.SilkS")
		)
		(fp_line
			(start 0.7874 -0.4064)
			(end 0.7874 0.4064)
			(stroke
				(width 0.1524)
				(type default)
			)
			(layer "F.SilkS")
		)
		(fp_line
			(start -0.7874 0.4064)
			(end -0.7874 -0.4064)
			(stroke
				(width 0.1524)
				(type default)
			)
			(layer "F.SilkS")
		)
		(fp_line
			(start -0.7874 -0.4064)
			(end 0.7874 -0.4064)
			(stroke
				(width 0.1524)
				(type default)
			)
			(layer "F.SilkS")
		)
		(fp_line
			(start 0.67945 0.3048)
			(end 0.120396 0.3048)
			(stroke
				(width 0.1)
				(type default)
			)
			(layer "F.Fab")
		)
		(fp_line
			(start 0.67945 -0.3048)
			(end 0.67945 0.3048)
			(stroke
				(width 0.1)
				(type default)
			)
			(layer "F.Fab")
		)
		(fp_line
			(start 0.12065 -0.2794)
			(end 0.12065 -0.3048)
			(stroke
				(width 0.1)
				(type default)
			)
			(layer "F.Fab")
		)
		(fp_line
			(start 0.12065 -0.3048)
			(end 0.67945 -0.3048)
			(stroke
				(width 0.1)
				(type default)
			)
			(layer "F.Fab")
		)
		(fp_line
			(start 0.120396 0.3048)
			(end 0.120396 0.2794)
			(stroke
				(width 0.1)
				(type default)
			)
			(layer "F.Fab")
		)
		(fp_line
			(start 0.120396 0.2794)
			(end -0.12065 0.2794)
			(stroke
				(width 0.1)
				(type default)
			)
			(layer "F.Fab")
		)
		(fp_line
			(start -0.12065 0.3048)
			(end -0.67945 0.3048)
			(stroke
				(width 0.1)
				(type default)
			)
			(layer "F.Fab")
		)
		(fp_line
			(start -0.12065 0.2794)
			(end -0.12065 0.3048)
			(stroke
				(width 0.1)
				(type default)
			)
			(layer "F.Fab")
		)
		(fp_line
			(start -0.12065 -0.2794)
			(end 0.12065 -0.2794)
			(stroke
				(width 0.1)
				(type default)
			)
			(layer "F.Fab")
		)
		(fp_line
			(start -0.12065 -0.305054)
			(end -0.12065 -0.2794)
			(stroke
				(width 0.1)
				(type default)
			)
			(layer "F.Fab")
		)
		(fp_line
			(start -0.67945 0.3048)
			(end -0.67945 -0.305054)
			(stroke
				(width 0.1)
				(type default)
			)
			(layer "F.Fab")
		)
		(fp_line
			(start -0.67945 -0.305054)
			(end -0.12065 -0.305054)
			(stroke
				(width 0.1)
				(type default)
			)
			(layer "F.Fab")
		)
		(pad "1" smd circle
			(at -0.40005 0 180)
			(size 0 0)
			(layers "F.Cu" "F.Mask" "F.Paste")
			(net "GND")
		)
		(pad "2" smd circle
			(at 0.40005 0 180)
			(size 0 0)
			(layers "F.Cu" "F.Mask" "F.Paste")
			(net "SSD13_PWRDIS_R")
		)
	)
	(footprint ""
		(layer "F.Cu")
		(at 14.286992 -444.739014 180)
		(property "Reference" "X2"
			(at -0.1778 -1.92913 180)
			(unlocked yes)
			(layer "F.SilkS")
			(effects
				(font
					(size 0.7874 0.5842)
					(thickness 0.1524)
				)
				(justify left)
			)
		)
		(property "Value" ""
			(at 0 0 180)
			(layer "F.Fab")
			(effects
				(font
					(size 1.27 1.27)
				)
			)
		)
		(property "Device Type" "TP_TDR_4P_FTS_MPKT4_H025P0200_IO_TP15_TP_TDR_4P_DIP"
			(at 1.30175 1.27 270)
			(unlocked yes)
			(layer "F.Fab")
			(hide yes)
			(effects
				(font
					(size 0.635 0.4064)
					(thickness 0.1524)
				)
			)
		)
		(property "User Part Number" "TP15"
			(at 1.30175 1.27 270)
			(unlocked yes)
			(layer "Cmts.User")
			(hide yes)
			(effects
				(font
					(size 0.635 0.4064)
					(thickness 0.1524)
				)
			)
		)
		(duplicate_pad_numbers_are_jumpers no)
		(fp_line
			(start 2.54 3.81)
			(end 2.54 3.6703)
			(stroke
				(width 0.1524)
				(type default)
			)
			(layer "F.SilkS")
		)
		(fp_line
			(start 2.54 1.4097)
			(end 2.54 1.1303)
			(stroke
				(width 0.1524)
				(type default)
			)
			(layer "F.SilkS")
		)
		(fp_line
			(start 2.54 -1.1303)
			(end 2.54 -1.27)
			(stroke
				(width 0.1524)
				(type default)
			)
			(layer "F.SilkS")
		)
		(fp_line
			(start 2.54 -1.27)
			(end 0 -1.27)
			(stroke
				(width 0.1524)
				(type default)
			)
			(layer "F.SilkS")
		)
		(fp_line
			(start 0 3.81)
			(end 2.54 3.81)
			(stroke
				(width 0.1524)
				(type default)
			)
			(layer "F.SilkS")
		)
		(fp_line
			(start 0 3.175)
			(end 0 3.81)
			(stroke
				(width 0.1524)
				(type default)
			)
			(layer "F.SilkS")
		)
		(fp_line
			(start 0 0.635)
			(end 0 1.905)
			(stroke
				(width 0.1524)
				(type default)
			)
			(layer "F.SilkS")
		)
		(fp_line
			(start 0 -1.27)
			(end 0 -0.635)
			(stroke
				(width 0.1524)
				(type default)
			)
			(layer "F.SilkS")
		)
		(fp_poly
			(pts
				(xy -0.761746 0) (xy -2.285746 -0.762) (xy -2.285746 0.762)
			)
			(stroke
				(width 0)
				(type default)
			)
			(fill yes)
			(layer "F.SilkS")
		)
		(fp_line
			(start 2.54 3.81)
			(end 2.54 -1.27)
			(stroke
				(width 0.1)
				(type default)
			)
			(layer "F.Fab")
		)
		(fp_line
			(start 2.54 -1.27)
			(end 0 -1.27)
			(stroke
				(width 0.1)
				(type default)
			)
			(layer "F.Fab")
		)
		(fp_line
			(start 0 3.81)
			(end 2.54 3.81)
			(stroke
				(width 0.1)
				(type default)
			)
			(layer "F.Fab")
		)
		(fp_line
			(start 0 -1.27)
			(end 0 3.81)
			(stroke
				(width 0.1)
				(type default)
			)
			(layer "F.Fab")
		)
		(fp_poly
			(pts
				(xy -0.761746 0) (xy -2.285746 -0.762) (xy -2.285746 0.762)
			)
			(stroke
				(width 0)
				(type default)
			)
			(fill yes)
			(layer "F.Fab")
		)
		(pad "1" thru_hole circle
			(at 0 0 180)
			(size 1.0033 1.0033)
			(drill 0.249936)
			(layers "*.Cu" "*.Mask")
			(remove_unused_layers no)
			(net "TDR_DIFF_85_TOP_DIP")
			(clearance 0.10795)
			(thermal_gap 0.10795)
			(padstack
				(mode front_inner_back)
				(layer "Inner"
					(shape circle)
					(size 0.8001 0.8001)
					(clearance 0.1524)
				)
				(layer "B.Cu"
					(shape circle)
					(size 1.0033 1.0033)
					(clearance 0.10795)
				)
			)
		)
		(pad "2" thru_hole circle
			(at 2.54 0 180)
			(size 1.9939 1.9939)
			(drill 0.249936)
			(layers "*.Cu" "*.Mask")
			(remove_unused_layers no)
			(net "COUPON_GND1")
			(clearance 0.10795)
			(thermal_gap 0.10795)
			(padstack
				(mode front_inner_back)
				(layer "Inner"
					(shape circle)
					(size 0.8001 0.8001)
					(clearance 0.1524)
				)
				(layer "B.Cu"
					(shape circle)
					(size 1.9939 1.9939)
					(clearance 0.10795)
				)
			)
		)
		(pad "3" thru_hole circle
			(at 2.54 2.54 180)
			(size 1.9939 1.9939)
			(drill 0.249936)
			(layers "*.Cu" "*.Mask")
			(remove_unused_layers no)
			(net "COUPON_GND1")
			(clearance 0.10795)
			(thermal_gap 0.10795)
			(padstack
				(mode front_inner_back)
				(layer "Inner"
					(shape circle)
					(size 0.8001 0.8001)
					(clearance 0.1524)
				)
				(layer "B.Cu"
					(shape circle)
					(size 1.9939 1.9939)
					(clearance 0.10795)
				)
			)
		)
		(pad "4" thru_hole circle
			(at 0 2.54 180)
			(size 1.0033 1.0033)
			(drill 0.249936)
			(layers "*.Cu" "*.Mask")
			(remove_unused_layers no)
			(net "TDR_DIFF_85_TOP_DIN")
			(clearance 0.10795)
			(thermal_gap 0.10795)
			(padstack
				(mode front_inner_back)
				(layer "Inner"
					(shape circle)
					(size 0.8001 0.8001)
					(clearance 0.1524)
				)
				(layer "B.Cu"
					(shape circle)
					(size 1.0033 1.0033)
					(clearance 0.10795)
				)
			)
		)
	)
	(footprint ""
		(layer "F.Cu")
		(at 333.502 -205.232 -90)
		(property "Reference" "R4116"
			(at 0 0 270)
			(layer "F.SilkS")
			(hide yes)
			(effects
				(font
					(size 1.27 1.27)
				)
			)
		)
		(property "Value" ""
			(at 0 0 270)
			(layer "F.Fab")
			(effects
				(font
					(size 1.27 1.27)
				)
			)
		)
		(duplicate_pad_numbers_are_jumpers no)
		(fp_line
			(start -0.7874 0.4064)
			(end -0.7874 -0.4064)
			(stroke
				(width 0.1524)
				(type default)
			)
			(layer "F.SilkS")
		)
		(fp_line
			(start 0.7874 0.4064)
			(end -0.7874 0.4064)
			(stroke
				(width 0.1524)
				(type default)
			)
			(layer "F.SilkS")
		)
		(fp_line
			(start -0.7874 -0.4064)
			(end 0.7874 -0.4064)
			(stroke
				(width 0.1524)
				(type default)
			)
			(layer "F.SilkS")
		)
		(fp_line
			(start 0.7874 -0.4064)
			(end 0.7874 0.4064)
			(stroke
				(width 0.1524)
				(type default)
			)
			(layer "F.SilkS")
		)
		(fp_line
			(start -0.67945 0.3048)
			(end -0.67945 -0.305054)
			(stroke
				(width 0.1)
				(type default)
			)
			(layer "F.Fab")
		)
		(fp_line
			(start -0.12065 0.3048)
			(end -0.67945 0.3048)
			(stroke
				(width 0.1)
				(type default)
			)
			(layer "F.Fab")
		)
		(fp_line
			(start 0.120396 0.3048)
			(end 0.120396 0.2794)
			(stroke
				(width 0.1)
				(type default)
			)
			(layer "F.Fab")
		)
		(fp_line
			(start 0.67945 0.3048)
			(end 0.120396 0.3048)
			(stroke
				(width 0.1)
				(type default)
			)
			(layer "F.Fab")
		)
		(fp_line
			(start -0.12065 0.2794)
			(end -0.12065 0.3048)
			(stroke
				(width 0.1)
				(type default)
			)
			(layer "F.Fab")
		)
		(fp_line
			(start 0.120396 0.2794)
			(end -0.12065 0.2794)
			(stroke
				(width 0.1)
				(type default)
			)
			(layer "F.Fab")
		)
		(fp_line
			(start -0.12065 -0.2794)
			(end 0.12065 -0.2794)
			(stroke
				(width 0.1)
				(type default)
			)
			(layer "F.Fab")
		)
		(fp_line
			(start 0.12065 -0.2794)
			(end 0.12065 -0.3048)
			(stroke
				(width 0.1)
				(type default)
			)
			(layer "F.Fab")
		)
		(fp_line
			(start 0.12065 -0.3048)
			(end 0.67945 -0.3048)
			(stroke
				(width 0.1)
				(type default)
			)
			(layer "F.Fab")
		)
		(fp_line
			(start 0.67945 -0.3048)
			(end 0.67945 0.3048)
			(stroke
				(width 0.1)
				(type default)
			)
			(layer "F.Fab")
		)
		(fp_line
			(start -0.67945 -0.305054)
			(end -0.12065 -0.305054)
			(stroke
				(width 0.1)
				(type default)
			)
			(layer "F.Fab")
		)
		(fp_line
			(start -0.12065 -0.305054)
			(end -0.12065 -0.2794)
			(stroke
				(width 0.1)
				(type default)
			)
			(layer "F.Fab")
		)
		(pad "1" smd circle
			(at -0.40005 0 270)
			(size 0 0)
			(layers "F.Cu" "F.Mask" "F.Paste")
			(net "SSD8_PWRDIS")
		)
		(pad "2" smd circle
			(at 0.40005 0 270)
			(size 0 0)
			(layers "F.Cu" "F.Mask" "F.Paste")
			(net "SSD8_PWRDIS_R")
		)
	)
	(footprint ""
		(layer "F.Cu")
		(at 141.458442 -250.070874 -90)
		(property "Reference" "R1276"
			(at 0 0 270)
			(layer "F.SilkS")
			(hide yes)
			(effects
				(font
					(size 1.27 1.27)
				)
			)
		)
		(property "Value" ""
			(at 0 0 270)
			(layer "F.Fab")
			(effects
				(font
					(size 1.27 1.27)
				)
			)
		)
		(duplicate_pad_numbers_are_jumpers no)
		(fp_line
			(start -0.7874 0.4064)
			(end -0.7874 -0.4064)
			(stroke
				(width 0.1524)
				(type default)
			)
			(layer "F.SilkS")
		)
		(fp_line
			(start 0.7874 0.4064)
			(end -0.7874 0.4064)
			(stroke
				(width 0.1524)
				(type default)
			)
			(layer "F.SilkS")
		)
		(fp_line
			(start -0.7874 -0.4064)
			(end 0.7874 -0.4064)
			(stroke
				(width 0.1524)
				(type default)
			)
			(layer "F.SilkS")
		)
		(fp_line
			(start 0.7874 -0.4064)
			(end 0.7874 0.4064)
			(stroke
				(width 0.1524)
				(type default)
			)
			(layer "F.SilkS")
		)
		(fp_line
			(start -0.67945 0.3048)
			(end -0.67945 -0.305054)
			(stroke
				(width 0.1)
				(type default)
			)
			(layer "F.Fab")
		)
		(fp_line
			(start -0.12065 0.3048)
			(end -0.67945 0.3048)
			(stroke
				(width 0.1)
				(type default)
			)
			(layer "F.Fab")
		)
		(fp_line
			(start 0.120396 0.3048)
			(end 0.120396 0.2794)
			(stroke
				(width 0.1)
				(type default)
			)
			(layer "F.Fab")
		)
		(fp_line
			(start 0.67945 0.3048)
			(end 0.120396 0.3048)
			(stroke
				(width 0.1)
				(type default)
			)
			(layer "F.Fab")
		)
		(fp_line
			(start -0.12065 0.2794)
			(end -0.12065 0.3048)
			(stroke
				(width 0.1)
				(type default)
			)
			(layer "F.Fab")
		)
		(fp_line
			(start 0.120396 0.2794)
			(end -0.12065 0.2794)
			(stroke
				(width 0.1)
				(type default)
			)
			(layer "F.Fab")
		)
		(fp_line
			(start -0.12065 -0.2794)
			(end 0.12065 -0.2794)
			(stroke
				(width 0.1)
				(type default)
			)
			(layer "F.Fab")
		)
		(fp_line
			(start 0.12065 -0.2794)
			(end 0.12065 -0.3048)
			(stroke
				(width 0.1)
				(type default)
			)
			(layer "F.Fab")
		)
		(fp_line
			(start 0.12065 -0.3048)
			(end 0.67945 -0.3048)
			(stroke
				(width 0.1)
				(type default)
			)
			(layer "F.Fab")
		)
		(fp_line
			(start 0.67945 -0.3048)
			(end 0.67945 0.3048)
			(stroke
				(width 0.1)
				(type default)
			)
			(layer "F.Fab")
		)
		(fp_line
			(start -0.67945 -0.305054)
			(end -0.12065 -0.305054)
			(stroke
				(width 0.1)
				(type default)
			)
			(layer "F.Fab")
		)
		(fp_line
			(start -0.12065 -0.305054)
			(end -0.12065 -0.2794)
			(stroke
				(width 0.1)
				(type default)
			)
			(layer "F.Fab")
		)
		(pad "1" smd circle
			(at -0.40005 0 270)
			(size 0 0)
			(layers "F.Cu" "F.Mask" "F.Paste")
			(net "PEX1_MODE_SEL7")
		)
		(pad "2" smd circle
			(at 0.40005 0 270)
			(size 0 0)
			(layers "F.Cu" "F.Mask" "F.Paste")
			(net "P1V8_PEX")
		)
	)
)
